(kicad_pcb
	(version 20260206)
	(generator "pcbnew")
	(generator_version "10.0")
	(general
		(thickness 1.6)
		(legacy_teardrops no)
	)
	(paper "A4")
	(title_block
		(title "v1-tray-backplane — T6M_tray_BP_c_1023_1120.brd")
		(comment 1 "Open CloudServer (Microsoft) / footprints 94-97 of 170")
	)
	(layers
		(0 "F.Cu" signal "TOP")
		(4 "In1.Cu" signal "GND")
		(6 "In2.Cu" signal "IN1")
		(8 "In3.Cu" signal "VCC")
		(10 "In4.Cu" signal "VCC1")
		(12 "In5.Cu" signal "IN2")
		(14 "In6.Cu" signal "GND1")
		(2 "B.Cu" signal "BOTTOM")
		(9 "F.Adhes" user "F.Adhesive")
		(11 "B.Adhes" user "B.Adhesive")
		(13 "F.Paste" user "Package Geometry/Pastemask Top")
		(15 "B.Paste" user "Package Geometry/Pastemask Bottom")
		(5 "F.SilkS" user "Ref Des/Silkscreen Top")
		(7 "B.SilkS" user "Ref Des/Silkscreen Bottom")
		(1 "F.Mask" user "Board Geometry/Soldermask Top")
		(3 "B.Mask" user "Board Geometry/Soldermask Bottom")
		(17 "Dwgs.User" user "User.Drawings")
		(19 "Cmts.User" user "User.Comments")
		(21 "Eco1.User" user "User.Eco1")
		(23 "Eco2.User" user "User.Eco2")
		(25 "Edge.Cuts" user "Board Geometry/Outline")
		(27 "Margin" user)
		(31 "F.CrtYd" user "Package Geometry/Place Bound Top")
		(29 "B.CrtYd" user "Package Geometry/Place Bound Bottom")
		(35 "F.Fab" user "Ref Des/Assembly Top")
		(33 "B.Fab" user "Ref Des/Assembly Bottom")
	)
	(footprint ""
		(layer "F.Cu")
		(at 351.208848 -24.348694 180)
		(property "Reference" "R25"
			(at 58.940192 4.27736 0)
			(unlocked yes)
			(layer "F.SilkS")
			(effects
				(font
					(size 0.7874 0.5842)
					(thickness 0.1524)
				)
				(justify left)
			)
		)
		(property "Value" ""
			(at 0 0 180)
			(layer "F.Fab")
			(effects
				(font
					(size 1.27 1.27)
				)
			)
		)
		(duplicate_pad_numbers_are_jumpers no)
		(fp_line
			(start 0.7874 0.4064)
			(end -0.7874 0.4064)
			(stroke
				(width 0.1524)
				(type default)
			)
			(layer "F.SilkS")
		)
		(fp_line
			(start 0.7874 -0.4064)
			(end 0.7874 0.4064)
			(stroke
				(width 0.1524)
				(type default)
			)
			(layer "F.SilkS")
		)
		(fp_line
			(start -0.7874 0.4064)
			(end -0.7874 -0.4064)
			(stroke
				(width 0.1524)
				(type default)
			)
			(layer "F.SilkS")
		)
		(fp_line
			(start -0.7874 -0.4064)
			(end 0.7874 -0.4064)
			(stroke
				(width 0.1524)
				(type default)
			)
			(layer "F.SilkS")
		)
		(fp_poly
			(pts
				(xy -0.508 0.2794) (xy -0.508 0.2286) (xy -0.635 0.2286) (xy -0.635 -0.254) (xy -0.5334 -0.254)
				(xy -0.5334 -0.2794) (xy 0.5334 -0.2794) (xy 0.5334 -0.254) (xy 0.635 -0.254) (xy 0.635 0.254) (xy 0.5334 0.254)
				(xy 0.5334 0.2794)
			)
			(stroke
				(width 0)
				(type default)
			)
			(fill no)
			(layer "F.CrtYd")
		)
		(pad "1" smd rect
			(at 0.40005 0 180)
			(size 0.4572 0.508)
			(layers "F.Cu" "F.Mask" "F.Paste")
			(net "P3V3_BLAD2")
		)
		(pad "2" smd rect
			(at -0.40005 0 180)
			(size 0.4572 0.508)
			(layers "F.Cu" "F.Mask" "F.Paste")
			(net "ENET10G_3_MOD_DEF0")
		)
	)
	(footprint ""
		(layer "F.Cu")
		(at 325.570088 -14.390116 180)
		(property "Reference" "U8"
			(at 5.929376 -10.501884 0)
			(unlocked yes)
			(layer "F.SilkS")
			(effects
				(font
					(size 0.7874 0.5842)
					(thickness 0.1524)
				)
				(justify left)
			)
		)
		(property "Value" ""
			(at 0 0 180)
			(layer "F.Fab")
			(effects
				(font
					(size 1.27 1.27)
				)
			)
		)
		(duplicate_pad_numbers_are_jumpers no)
		(fp_line
			(start 5.500116 3.700018)
			(end 4.191 3.700018)
			(stroke
				(width 0.1524)
				(type default)
			)
			(layer "F.SilkS")
		)
		(fp_line
			(start 5.500116 0.889)
			(end 5.500116 3.700018)
			(stroke
				(width 0.1524)
				(type default)
			)
			(layer "F.SilkS")
		)
		(fp_line
			(start 5.500116 -3.700018)
			(end 5.500116 -0.889)
			(stroke
				(width 0.1524)
				(type default)
			)
			(layer "F.SilkS")
		)
		(fp_line
			(start 3.7846 -3.700018)
			(end 5.500116 -3.700018)
			(stroke
				(width 0.1524)
				(type default)
			)
			(layer "F.SilkS")
		)
		(fp_line
			(start -3.7846 3.700018)
			(end -5.500116 3.700018)
			(stroke
				(width 0.1524)
				(type default)
			)
			(layer "F.SilkS")
		)
		(fp_line
			(start -5.500116 0.635)
			(end -5.500116 3.700018)
			(stroke
				(width 0.1524)
				(type default)
			)
			(layer "F.SilkS")
		)
		(fp_line
			(start -5.500116 -3.700018)
			(end -4.191 -3.700018)
			(stroke
				(width 0.1524)
				(type default)
			)
			(layer "F.SilkS")
		)
		(fp_line
			(start -5.500116 -3.700018)
			(end -5.500116 -0.635)
			(stroke
				(width 0.1524)
				(type default)
			)
			(layer "F.SilkS")
		)
		(fp_poly
			(pts
				(xy -3.387344 5.3848) (xy -3.946144 6.8072) (xy -2.853944 6.8072)
			)
			(stroke
				(width 0)
				(type default)
			)
			(fill yes)
			(layer "F.SilkS")
		)
		(fp_poly
			(pts
				(arc
					(start -4.064 -0.3302)
					(mid -4.8006 -1.0668)
					(end -5.5372 -0.3302)
				)
				(arc
					(start -5.5372 0.3048)
					(mid -5.314015 0.843615)
					(end -4.7752 1.0668)
				)
				(arc
					(start -4.7752 1.0668)
					(mid -4.272306 0.858494)
					(end -4.064 0.3556)
				)
			)
			(stroke
				(width 0)
				(type default)
			)
			(fill no)
			(layer "B.CrtYd")
		)
		(fp_poly
			(pts
				(arc
					(start 3.7338 0)
					(mid 5.8674 0)
					(end 3.7338 0)
				)
			)
			(stroke
				(width 0)
				(type default)
			)
			(fill no)
			(layer "B.CrtYd")
		)
		(fp_rect
			(start -5.5118 5.1308)
			(end 5.5118 -5.1308)
			(stroke
				(width 0)
				(type default)
			)
			(fill no)
			(layer "F.CrtYd")
		)
		(fp_text user "10"
			(at 5.105146 6.460998 0)
			(unlocked yes)
			(layer "F.SilkS")
			(effects
				(font
					(size 0.7874 0.5842)
					(thickness 0.1524)
				)
				(justify left)
			)
		)
		(fp_text user "11"
			(at 3.292602 -6.421374 90)
			(unlocked yes)
			(layer "F.SilkS")
			(effects
				(font
					(size 0.7874 0.5842)
					(thickness 0.1524)
				)
				(justify left)
			)
		)
		(fp_text user "1"
			(at -3.90525 5.927598 0)
			(unlocked yes)
			(layer "F.SilkS")
			(effects
				(font
					(size 0.7874 0.5842)
					(thickness 0.1524)
				)
				(justify left)
			)
		)
		(fp_text user "20"
			(at -4.073398 -8.377174 90)
			(unlocked yes)
			(layer "F.SilkS")
			(effects
				(font
					(size 0.7874 0.5842)
					(thickness 0.1524)
				)
				(justify left)
			)
		)
		(pad "" np_thru_hole oval
			(at -4.800092 0 180)
			(size 0.9652 1.6002)
			(drill oval 0.9652 1.6002)
			(layers "*.Cu" "*.Mask")
			(clearance 0.381)
			(thermal_gap 0.381)
		)
		(pad "" np_thru_hole circle
			(at 4.800092 0 180)
			(size 1.6002 1.6002)
			(drill 1.6002)
			(layers "*.Cu" "*.Mask")
			(clearance 0.381)
			(thermal_gap 0.381)
		)
		(pad "1" smd oval
			(at -3.400044 4.100068 180)
			(size 0.508 2.032)
			(layers "F.Cu" "F.Mask" "F.Paste")
			(net "GND")
		)
		(pad "2" smd oval
			(at -2.599944 4.100068 180)
			(size 0.508 2.032)
			(layers "F.Cu" "F.Mask" "F.Paste")
			(net "ENET10G_4_TX_FAULT")
		)
		(pad "3" smd oval
			(at -1.800098 4.100068 180)
			(size 0.508 2.032)
			(layers "F.Cu" "F.Mask" "F.Paste")
			(net "ENET10G_4_TX_DIS")
		)
		(pad "4" smd oval
			(at -0.999998 4.100068 180)
			(size 0.508 2.032)
			(layers "F.Cu" "F.Mask" "F.Paste")
			(net "ENET10G_4_SDA")
		)
		(pad "5" smd oval
			(at -0.199898 4.100068 180)
			(size 0.508 2.032)
			(layers "F.Cu" "F.Mask" "F.Paste")
			(net "ENET10G_4_SCL")
		)
		(pad "6" smd oval
			(at 0.599948 4.100068 180)
			(size 0.508 2.032)
			(layers "F.Cu" "F.Mask" "F.Paste")
			(net "ENET10G_4_MOD_DEF0")
		)
		(pad "7" smd oval
			(at 1.400048 4.100068 180)
			(size 0.508 2.032)
			(layers "F.Cu" "F.Mask" "F.Paste")
			(net "ENET10G_4_RS0")
		)
		(pad "8" smd oval
			(at 2.199894 4.100068 180)
			(size 0.508 2.032)
			(layers "F.Cu" "F.Mask" "F.Paste")
			(net "ENET10G_4_LOS")
		)
		(pad "9" smd oval
			(at 2.999994 4.100068 180)
			(size 0.508 2.032)
			(layers "F.Cu" "F.Mask" "F.Paste")
			(net "ENET10G_4_RS1")
		)
		(pad "10" smd oval
			(at 3.800094 4.100068 180)
			(size 0.508 2.032)
			(layers "F.Cu" "F.Mask" "F.Paste")
			(net "GND")
		)
		(pad "11" smd oval
			(at 3.400044 -4.100068 180)
			(size 0.508 2.032)
			(layers "F.Cu" "F.Mask" "F.Paste")
			(net "GND")
		)
		(pad "12" smd oval
			(at 2.599944 -4.100068 180)
			(size 0.508 2.032)
			(layers "F.Cu" "F.Mask" "F.Paste")
			(net "ENET10G_4_RDN")
		)
		(pad "13" smd oval
			(at 1.800098 -4.100068 180)
			(size 0.508 2.032)
			(layers "F.Cu" "F.Mask" "F.Paste")
			(net "ENET10G_4_RDP")
		)
		(pad "14" smd oval
			(at 0.999998 -4.100068 180)
			(size 0.508 2.032)
			(layers "F.Cu" "F.Mask" "F.Paste")
			(net "GND")
		)
		(pad "15" smd oval
			(at 0.199898 -4.100068 180)
			(size 0.508 2.032)
			(layers "F.Cu" "F.Mask" "F.Paste")
			(net "P3V3_10G_4_VCCR")
		)
		(pad "16" smd oval
			(at -0.599948 -4.100068 180)
			(size 0.508 2.032)
			(layers "F.Cu" "F.Mask" "F.Paste")
			(net "P3V3_10G_4_VCCT")
		)
		(pad "17" smd oval
			(at -1.400048 -4.100068 180)
			(size 0.508 2.032)
			(layers "F.Cu" "F.Mask" "F.Paste")
			(net "GND")
		)
		(pad "18" smd oval
			(at -2.199894 -4.100068 180)
			(size 0.508 2.032)
			(layers "F.Cu" "F.Mask" "F.Paste")
			(net "ENET10G_4_TDP")
		)
		(pad "19" smd oval
			(at -2.999994 -4.100068 180)
			(size 0.508 2.032)
			(layers "F.Cu" "F.Mask" "F.Paste")
			(net "ENET10G_4_TDN")
		)
		(pad "20" smd oval
			(at -3.800094 -4.100068 180)
			(size 0.508 2.032)
			(layers "F.Cu" "F.Mask" "F.Paste")
			(net "GND")
		)
		(zone
			(layers "F.Cu" "B.Cu" "In1.Cu" "In2.Cu" "In3.Cu" "In4.Cu" "In5.Cu" "In6.Cu")
			(hatch none 0.5)
			(connect_pads
				(clearance 0)
			)
			(min_thickness 0.25)
			(keepout
				(tracks not_allowed)
				(vias allowed)
				(pads allowed)
				(copperpour not_allowed)
				(footprints allowed)
			)
			(placement
				(enabled no)
				(sheetname "")
			)
			(fill
				(thermal_gap 0.5)
				(thermal_bridge_width 0.5)
				(island_removal_mode 0)
			)
			(polygon
				(pts
					(arc
						(start 330.345288 -15.609316)
						(mid 330.991866 -15.341494)
						(end 331.259688 -14.694916)
					)
					(arc
						(start 331.259688 -14.059916)
						(mid 330.370688 -13.170916)
						(end 329.481688 -14.059916)
					)
					(arc
						(start 329.481688 -14.745716)
						(mid 329.734631 -15.356373)
						(end 330.345288 -15.609316)
					)
				)
			)
		)
		(zone
			(layers "F.Cu" "B.Cu" "In1.Cu" "In2.Cu" "In3.Cu" "In4.Cu" "In5.Cu" "In6.Cu")
			(hatch none 0.5)
			(connect_pads
				(clearance 0)
			)
			(min_thickness 0.25)
			(keepout
				(tracks not_allowed)
				(vias allowed)
				(pads allowed)
				(copperpour not_allowed)
				(footprints allowed)
			)
			(placement
				(enabled no)
				(sheetname "")
			)
			(fill
				(thermal_gap 0.5)
				(thermal_bridge_width 0.5)
				(island_removal_mode 0)
			)
			(polygon
				(pts
					(arc
						(start 321.988688 -14.390116)
						(mid 319.550288 -14.390116)
						(end 321.988688 -14.390116)
					)
				)
			)
		)
	)
	(footprint ""
		(layer "F.Cu")
		(at 28.437332 -16.383 90)
		(property "Reference" "R85"
			(at -3.7846 -0.371348 90)
			(unlocked yes)
			(layer "F.SilkS")
			(effects
				(font
					(size 0.7874 0.5842)
					(thickness 0.1524)
				)
				(justify left)
			)
		)
		(property "Value" ""
			(at 0 0 90)
			(layer "F.Fab")
			(effects
				(font
					(size 1.27 1.27)
				)
			)
		)
		(duplicate_pad_numbers_are_jumpers no)
		(fp_line
			(start 0.7874 -0.4064)
			(end 0.7874 0.4064)
			(stroke
				(width 0.1524)
				(type default)
			)
			(layer "F.SilkS")
		)
		(fp_line
			(start -0.7874 -0.4064)
			(end 0.7874 -0.4064)
			(stroke
				(width 0.1524)
				(type default)
			)
			(layer "F.SilkS")
		)
		(fp_line
			(start 0.7874 0.4064)
			(end -0.7874 0.4064)
			(stroke
				(width 0.1524)
				(type default)
			)
			(layer "F.SilkS")
		)
		(fp_line
			(start -0.7874 0.4064)
			(end -0.7874 -0.4064)
			(stroke
				(width 0.1524)
				(type default)
			)
			(layer "F.SilkS")
		)
		(fp_poly
			(pts
				(xy -0.508 0.2794) (xy -0.508 0.2286) (xy -0.635 0.2286) (xy -0.635 -0.254) (xy -0.5334 -0.254)
				(xy -0.5334 -0.2794) (xy 0.5334 -0.2794) (xy 0.5334 -0.254) (xy 0.635 -0.254) (xy 0.635 0.254) (xy 0.5334 0.254)
				(xy 0.5334 0.2794)
			)
			(stroke
				(width 0)
				(type default)
			)
			(fill no)
			(layer "F.CrtYd")
		)
		(pad "1" smd rect
			(at 0.40005 0 90)
			(size 0.4572 0.508)
			(layers "F.Cu" "F.Mask" "F.Paste")
			(net "N39386877")
		)
		(pad "2" smd rect
			(at -0.40005 0 90)
			(size 0.4572 0.508)
			(layers "F.Cu" "F.Mask" "F.Paste")
			(net "GND")
		)
	)
	(footprint ""
		(layer "F.Cu")
		(at 4.500118 -4.700016 180)
		(property "Reference" "H7"
			(at -8.474964 -0.926084 0)
			(unlocked yes)
			(layer "F.SilkS")
			(effects
				(font
					(size 0.7874 0.5842)
					(thickness 0.1524)
				)
				(justify left)
			)
		)
		(property "Value" ""
			(at 0 0 180)
			(layer "F.Fab")
			(effects
				(font
					(size 1.27 1.27)
				)
			)
		)
		(duplicate_pad_numbers_are_jumpers no)
		(fp_circle
			(center 0 0)
			(end -7.999984 0)
			(stroke
				(width 0.1524)
				(type default)
			)
			(fill no)
			(layer "F.SilkS")
		)
		(fp_arc
			(start 14.5034 0)
			(mid -13.07281 6.291111)
			(end 9.04875 -11.334496)
			(stroke
				(width 0.1524)
				(type default)
			)
			(layer "B.SilkS")
		)
		(fp_arc
			(start 9.463786 -10.990072)
			(mid 13.183363 -6.045203)
			(end 14.5034 0)
			(stroke
				(width 0.1524)
				(type default)
			)
			(layer "B.SilkS")
		)
		(fp_arc
			(start 7.999984 0)
			(mid 7.105874 3.675179)
			(end 4.623308 6.528816)
			(stroke
				(width 0.1524)
				(type default)
			)
			(layer "B.SilkS")
		)
		(fp_arc
			(start -4.623308 6.528816)
			(mid -3.675184 -7.105826)
			(end 7.999984 0)
			(stroke
				(width 0.1524)
				(type default)
			)
			(layer "B.SilkS")
		)
		(fp_poly
			(pts
				(arc
					(start -4.5085 0)
					(mid 4.5085 0)
					(end -4.5085 0)
				)
			)
			(stroke
				(width 0)
				(type default)
			)
			(fill no)
			(layer "F.CrtYd")
		)
		(pad "" np_thru_hole circle
			(at 0 0 180)
			(size 3.6068 3.6068)
			(drill 3.6068)
			(layers "*.Cu" "*.Mask")
			(clearance 0.381)
			(thermal_gap 0.381)
		)
		(pad "2" thru_hole circle
			(at 3.41122 0 180)
			(size 0.762 0.762)
			(drill 0.5588)
			(layers "*.Cu" "*.Mask")
			(remove_unused_layers no)
			(net "GND")
			(clearance 0.1524)
			(thermal_gap 0.1524)
		)
		(pad "3" thru_hole circle
			(at 2.411984 -2.411984 180)
			(size 0.762 0.762)
			(drill 0.5588)
			(layers "*.Cu" "*.Mask")
			(remove_unused_layers no)
			(net "GND")
			(clearance 0.1524)
			(thermal_gap 0.1524)
		)
		(pad "4" thru_hole circle
			(at 0 -3.41122 180)
			(size 0.762 0.762)
			(drill 0.5588)
			(layers "*.Cu" "*.Mask")
			(remove_unused_layers no)
			(net "GND")
			(clearance 0.1524)
			(thermal_gap 0.1524)
		)
		(pad "5" thru_hole circle
			(at -2.411984 -2.411984 180)
			(size 0.762 0.762)
			(drill 0.5588)
			(layers "*.Cu" "*.Mask")
			(remove_unused_layers no)
			(net "GND")
			(clearance 0.1524)
			(thermal_gap 0.1524)
		)
		(pad "6" thru_hole circle
			(at -3.41122 0 180)
			(size 0.762 0.762)
			(drill 0.5588)
			(layers "*.Cu" "*.Mask")
			(remove_unused_layers no)
			(net "GND")
			(clearance 0.1524)
			(thermal_gap 0.1524)
		)
		(pad "7" thru_hole circle
			(at -2.411984 2.411984 180)
			(size 0.762 0.762)
			(drill 0.5588)
			(layers "*.Cu" "*.Mask")
			(remove_unused_layers no)
			(net "GND")
			(clearance 0.1524)
			(thermal_gap 0.1524)
		)
		(pad "8" thru_hole circle
			(at 0 3.41122 180)
			(size 0.762 0.762)
			(drill 0.5588)
			(layers "*.Cu" "*.Mask")
			(remove_unused_layers no)
			(net "GND")
			(clearance 0.1524)
			(thermal_gap 0.1524)
		)
		(pad "9" thru_hole circle
			(at 2.411984 2.411984 180)
			(size 0.762 0.762)
			(drill 0.5588)
			(layers "*.Cu" "*.Mask")
			(remove_unused_layers no)
			(net "GND")
			(clearance 0.1524)
			(thermal_gap 0.1524)
		)
		(zone
			(layer "F.Cu")
			(hatch none 0.5)
			(connect_pads
				(clearance 0)
			)
			(min_thickness 0.25)
			(keepout
				(tracks not_allowed)
				(vias allowed)
				(pads allowed)
				(copperpour not_allowed)
				(footprints allowed)
			)
			(placement
				(enabled no)
				(sheetname "")
			)
			(fill
				(thermal_gap 0.5)
				(thermal_bridge_width 0.5)
				(island_removal_mode 0)
			)
			(polygon
				(pts
					(arc
						(start 4.500118 3.299968)
						(mid -1.156725 0.956827)
						(end -3.499866 -4.700016)
					)
					(arc
						(start -3.499866 -4.700016)
						(mid -1.156725 -10.356859)
						(end 4.500118 -12.7)
					)
					(arc
						(start 4.500118 -9.462516)
						(mid -0.262382 -4.700016)
						(end 4.500118 0.062484)
					)
				)
			)
		)
		(zone
			(layers "F.Cu" "B.Cu" "In1.Cu" "In2.Cu" "In3.Cu" "In4.Cu" "In5.Cu" "In6.Cu")
			(hatch none 0.5)
			(connect_pads
				(clearance 0)
			)
			(min_thickness 0.25)
			(keepout
				(tracks not_allowed)
				(vias allowed)
				(pads allowed)
				(copperpour not_allowed)
				(footprints allowed)
			)
			(placement
				(enabled no)
				(sheetname "")
			)
			(fill
				(thermal_gap 0.5)
				(thermal_bridge_width 0.5)
				(island_removal_mode 0)
			)
			(polygon
				(pts
					(arc
						(start 6.811518 -4.700016)
						(mid 2.188718 -4.700016)
						(end 6.811518 -4.700016)
					)
				)
			)
		)
		(zone
			(layer "B.Cu")
			(hatch none 0.5)
			(connect_pads
				(clearance 0)
			)
			(min_thickness 0.25)
			(keepout
				(tracks not_allowed)
				(vias allowed)
				(pads allowed)
				(copperpour not_allowed)
				(footprints allowed)
			)
			(placement
				(enabled no)
				(sheetname "")
			)
			(fill
				(thermal_gap 0.5)
				(thermal_bridge_width 0.5)
				(island_removal_mode 0)
			)
			(polygon
				(pts
					(arc
						(start 4.500118 -15.225522)
						(mid 1.300094 -13.900028)
						(end -0.0254 -10.700004)
					)
					(arc
						(start -0.0254 -4.700016)
						(mid 1.300094 -1.499992)
						(end 4.500118 -0.174498)
					)
					(arc
						(start 4.500118 0.308102)
						(mid 0.958844 -1.158742)
						(end -0.508 -4.700016)
					)
					(arc
						(start -0.508 -10.700004)
						(mid 0.958934 -14.241114)
						(end 4.500118 -15.707868)
					)
				)
			)
		)
		(zone
			(layer "B.Cu")
			(hatch none 0.5)
			(connect_pads
				(clearance 0)
			)
			(min_thickness 0.25)
			(keepout
				(tracks not_allowed)
				(vias allowed)
				(pads allowed)
				(copperpour not_allowed)
				(footprints allowed)
			)
			(placement
				(enabled no)
				(sheetname "")
			)
			(fill
				(thermal_gap 0.5)
				(thermal_bridge_width 0.5)
				(island_removal_mode 0)
			)
			(polygon
				(pts
					(arc
						(start 4.500118 -15.225522)
						(mid 7.700142 -13.900028)
						(end 9.025636 -10.700004)
					)
					(arc
						(start 9.025636 -4.700016)
						(mid 7.700142 -1.499992)
						(end 4.500118 -0.174498)
					)
					(arc
						(start 4.500118 0.308102)
						(mid 8.041392 -1.158742)
						(end 9.508236 -4.700016)
					)
					(arc
						(start 9.508236 -10.700004)
						(mid 8.041302 -14.241114)
						(end 4.500118 -15.707868)
					)
				)
			)
		)
	)
)
